# SCM (Grand Teton) — schematic netlist excerpt (pin names and nets, part order shuffled) for the footprints in the layout excerpt that follows; sources: Cadence DE-HDL packaged netlist, KiCad conversion of 12092022_DA0F0TMDCD0_F0T_Management_Board_D_brd_V3_OCP.brd

L4  Q_INDUCTOR  BLM18PG121SN1D/2000MA IND  pkg SMLF  page 15 : \1\ = P3V3_AUX ; \2\ = P3V3_BMC_USB2AV33
L15  Q_INDUCTOR  BLM18PG121SN1D/2000MA IND  pkg SMLF  page 17 : \1\ = P1V0_AUX ; \2\ = P1V0_STBY_DP_VCC10A

(kicad_pcb
	(version 20260206)
	(generator "pcbnew")
	(generator_version "10.0")
	(general
		(thickness 1.6)
		(legacy_teardrops no)
	)
	(paper "A4")
	(title_block
		(title "12092022_DA0F0TMDCD0_F0T_Management_Board_D_brd_V3_OCP.brd")
		(comment 1 "Grand Teton / footprints 847-848 of 1440")
	)
	(layers
		(0 "F.Cu" signal "TOP")
		(4 "In1.Cu" signal "GND")
		(6 "In2.Cu" signal "IN1")
		(8 "In3.Cu" signal "GND1")
		(10 "In4.Cu" signal "IN2")
		(12 "In5.Cu" signal "VCC")
		(14 "In6.Cu" signal "VCC1")
		(16 "In7.Cu" signal "IN3")
		(18 "In8.Cu" signal "GND2")
		(20 "In9.Cu" signal "IN4")
		(22 "In10.Cu" signal "GND3")
		(2 "B.Cu" signal "BOTTOM")
		(9 "F.Adhes" user "F.Adhesive")
		(11 "B.Adhes" user "B.Adhesive")
		(13 "F.Paste" user "Package Geometry/Pastemask Top")
		(15 "B.Paste" user "Package Geometry/Pastemask Bottom")
		(5 "F.SilkS" user "Ref Des/Silkscreen Top")
		(7 "B.SilkS" user "Ref Des/Silkscreen Bottom")
		(1 "F.Mask" user "Board Geometry/Soldermask Top")
		(3 "B.Mask" user "Board Geometry/Soldermask Bottom")
		(17 "Dwgs.User" user "User.Drawings")
		(19 "Cmts.User" user "User.Comments")
		(21 "Eco1.User" user "User.Eco1")
		(23 "Eco2.User" user "User.Eco2")
		(25 "Edge.Cuts" user "Board Geometry/Outline")
		(27 "Margin" user)
		(31 "F.CrtYd" user "Package Geometry/Place Bound Top")
		(29 "B.CrtYd" user "Package Geometry/Place Bound Bottom")
		(35 "F.Fab" user "Ref Des/Assembly Top")
		(33 "B.Fab" user "Ref Des/Assembly Bottom")
	)
	(footprint ""
		(layer "B.Cu")
		(at 67.70878 -34.155126 -90)
		(property "Reference" "L4"
			(at 0 0 90)
			(layer "B.SilkS")
			(hide yes)
			(effects
				(font
					(size 1.27 1.27)
				)
				(justify mirror)
			)
		)
		(property "Value" ""
			(at 0 0 90)
			(layer "B.Fab")
			(effects
				(font
					(size 1.27 1.27)
				)
				(justify mirror)
			)
		)
		(duplicate_pad_numbers_are_jumpers no)
		(fp_line
			(start -1.27 0.5842)
			(end 1.27 0.5842)
			(stroke
				(width 0.1524)
				(type default)
			)
			(layer "B.SilkS")
		)
		(fp_line
			(start -1.27 0.5842)
			(end -1.27 -0.5842)
			(stroke
				(width 0.1524)
				(type default)
			)
			(layer "B.SilkS")
		)
		(fp_line
			(start -0.127 0.5842)
			(end -0.127 -0.5842)
			(stroke
				(width 0.1524)
				(type default)
			)
			(layer "B.SilkS")
		)
		(fp_line
			(start 0.127 0.5842)
			(end 0.127 -0.5842)
			(stroke
				(width 0.1524)
				(type default)
			)
			(layer "B.SilkS")
		)
		(fp_line
			(start 1.27 0.5842)
			(end 1.27 -0.5842)
			(stroke
				(width 0.1524)
				(type default)
			)
			(layer "B.SilkS")
		)
		(fp_line
			(start 1.27 -0.5588)
			(end 1.27 -0.5842)
			(stroke
				(width 0.1524)
				(type default)
			)
			(layer "B.SilkS")
		)
		(fp_line
			(start 1.27 -0.5842)
			(end -1.27 -0.5842)
			(stroke
				(width 0.1524)
				(type default)
			)
			(layer "B.SilkS")
		)
		(fp_line
			(start -0.9144 0.508)
			(end 0.9144 0.508)
			(stroke
				(width 0.1)
				(type default)
			)
			(layer "B.Fab")
		)
		(fp_line
			(start 0.9144 0.508)
			(end 0.9144 0.406654)
			(stroke
				(width 0.1)
				(type default)
			)
			(layer "B.Fab")
		)
		(fp_line
			(start 0.9144 0.406654)
			(end 1.194308 0.406654)
			(stroke
				(width 0.1)
				(type default)
			)
			(layer "B.Fab")
		)
		(fp_line
			(start 1.194308 0.406654)
			(end 1.194308 -0.406654)
			(stroke
				(width 0.1)
				(type default)
			)
			(layer "B.Fab")
		)
		(fp_line
			(start -1.1938 0.4064)
			(end -0.9144 0.4064)
			(stroke
				(width 0.1)
				(type default)
			)
			(layer "B.Fab")
		)
		(fp_line
			(start -0.9144 0.4064)
			(end -0.9144 0.508)
			(stroke
				(width 0.1)
				(type default)
			)
			(layer "B.Fab")
		)
		(fp_line
			(start -1.1938 -0.406654)
			(end -1.1938 0.4064)
			(stroke
				(width 0.1)
				(type default)
			)
			(layer "B.Fab")
		)
		(fp_line
			(start -0.9144 -0.406654)
			(end -1.1938 -0.406654)
			(stroke
				(width 0.1)
				(type default)
			)
			(layer "B.Fab")
		)
		(fp_line
			(start 0.9144 -0.406654)
			(end 0.9144 -0.508)
			(stroke
				(width 0.1)
				(type default)
			)
			(layer "B.Fab")
		)
		(fp_line
			(start 1.194308 -0.406654)
			(end 0.9144 -0.406654)
			(stroke
				(width 0.1)
				(type default)
			)
			(layer "B.Fab")
		)
		(fp_line
			(start -0.9144 -0.508)
			(end -0.9144 -0.406654)
			(stroke
				(width 0.1)
				(type default)
			)
			(layer "B.Fab")
		)
		(fp_line
			(start 0.9144 -0.508)
			(end -0.9144 -0.508)
			(stroke
				(width 0.1)
				(type default)
			)
			(layer "B.Fab")
		)
		(pad "1" smd rect
			(at 0.7366 0 180)
			(size 0.7112 0.8128)
			(layers "B.Cu" "B.Mask" "B.Paste")
			(net "P3V3_AUX")
		)
		(pad "2" smd rect
			(at -0.7366 0 180)
			(size 0.7112 0.8128)
			(layers "B.Cu" "B.Mask" "B.Paste")
			(net "P3V3_BMC_USB2AV33")
		)
	)
	(footprint ""
		(layer "B.Cu")
		(at 73.431908 -58.038492 -90)
		(property "Reference" "L15"
			(at 0 0 90)
			(layer "B.SilkS")
			(hide yes)
			(effects
				(font
					(size 1.27 1.27)
				)
				(justify mirror)
			)
		)
		(property "Value" ""
			(at 0 0 90)
			(layer "B.Fab")
			(effects
				(font
					(size 1.27 1.27)
				)
				(justify mirror)
			)
		)
		(duplicate_pad_numbers_are_jumpers no)
		(fp_line
			(start -1.27 0.5842)
			(end 1.27 0.5842)
			(stroke
				(width 0.1524)
				(type default)
			)
			(layer "B.SilkS")
		)
		(fp_line
			(start -1.27 0.5842)
			(end -1.27 -0.5842)
			(stroke
				(width 0.1524)
				(type default)
			)
			(layer "B.SilkS")
		)
		(fp_line
			(start -0.127 0.5842)
			(end -0.127 -0.5842)
			(stroke
				(width 0.1524)
				(type default)
			)
			(layer "B.SilkS")
		)
		(fp_line
			(start 0.127 0.5842)
			(end 0.127 -0.5842)
			(stroke
				(width 0.1524)
				(type default)
			)
			(layer "B.SilkS")
		)
		(fp_line
			(start 1.27 0.5842)
			(end 1.27 -0.5842)
			(stroke
				(width 0.1524)
				(type default)
			)
			(layer "B.SilkS")
		)
		(fp_line
			(start 1.27 -0.5588)
			(end 1.27 -0.5842)
			(stroke
				(width 0.1524)
				(type default)
			)
			(layer "B.SilkS")
		)
		(fp_line
			(start 1.27 -0.5842)
			(end -1.27 -0.5842)
			(stroke
				(width 0.1524)
				(type default)
			)
			(layer "B.SilkS")
		)
		(fp_line
			(start -0.9144 0.508)
			(end 0.9144 0.508)
			(stroke
				(width 0.1)
				(type default)
			)
			(layer "B.Fab")
		)
		(fp_line
			(start 0.9144 0.508)
			(end 0.9144 0.406654)
			(stroke
				(width 0.1)
				(type default)
			)
			(layer "B.Fab")
		)
		(fp_line
			(start 0.9144 0.406654)
			(end 1.194308 0.406654)
			(stroke
				(width 0.1)
				(type default)
			)
			(layer "B.Fab")
		)
		(fp_line
			(start 1.194308 0.406654)
			(end 1.194308 -0.406654)
			(stroke
				(width 0.1)
				(type default)
			)
			(layer "B.Fab")
		)
		(fp_line
			(start -1.1938 0.4064)
			(end -0.9144 0.4064)
			(stroke
				(width 0.1)
				(type default)
			)
			(layer "B.Fab")
		)
		(fp_line
			(start -0.9144 0.4064)
			(end -0.9144 0.508)
			(stroke
				(width 0.1)
				(type default)
			)
			(layer "B.Fab")
		)
		(fp_line
			(start -1.1938 -0.406654)
			(end -1.1938 0.4064)
			(stroke
				(width 0.1)
				(type default)
			)
			(layer "B.Fab")
		)
		(fp_line
			(start -0.9144 -0.406654)
			(end -1.1938 -0.406654)
			(stroke
				(width 0.1)
				(type default)
			)
			(layer "B.Fab")
		)
		(fp_line
			(start 0.9144 -0.406654)
			(end 0.9144 -0.508)
			(stroke
				(width 0.1)
				(type default)
			)
			(layer "B.Fab")
		)
		(fp_line
			(start 1.194308 -0.406654)
			(end 0.9144 -0.406654)
			(stroke
				(width 0.1)
				(type default)
			)
			(layer "B.Fab")
		)
		(fp_line
			(start -0.9144 -0.508)
			(end -0.9144 -0.406654)
			(stroke
				(width 0.1)
				(type default)
			)
			(layer "B.Fab")
		)
		(fp_line
			(start 0.9144 -0.508)
			(end -0.9144 -0.508)
			(stroke
				(width 0.1)
				(type default)
			)
			(layer "B.Fab")
		)
		(pad "1" smd rect
			(at 0.7366 0 180)
			(size 0.7112 0.8128)
			(layers "B.Cu" "B.Mask" "B.Paste")
			(net "P1V0_AUX")
		)
		(pad "2" smd rect
			(at -0.7366 0 180)
			(size 0.7112 0.8128)
			(layers "B.Cu" "B.Mask" "B.Paste")
			(net "P1V0_STBY_DP_VCC10A")
		)
	)
)
